# S9S_MB_2U (Grand Teton) — schematic netlist excerpt (pin names and nets, part order shuffled) for the footprints in the layout excerpt that follows; sources: Cadence DE-HDL packaged netlist, KiCad conversion of 03242023_DA0F0TMBIJ0_F0T_Motherboard_J_brd_V01_OCP.brd

PR132  Q_RES  8.87K 1% EMPTY  pkg 0402LF  page 270 : A = PVCCIN_CPU0_LSET8 ; B = GND
R1351  Q_RES  100K 1% CHIP  pkg 0402LF  page 154 : A = RMII_OCP_BMC_RXD_0 ; B = GND
C963  Q_CAP_DIFFBUS  DIFF BUS_0.22UF 6.3V 20% X6S  pkg C0201  page 173 : \1\ = P5E_CPU0_PE2_TX_C_DP<1> ; \2\ = P5E_CPU0_PE2_TX_DP<1>

(kicad_pcb
	(version 20260206)
	(generator "pcbnew")
	(generator_version "10.0")
	(general
		(thickness 1.6)
		(legacy_teardrops no)
	)
	(paper "A4")
	(title_block
		(title "03242023_DA0F0TMBIJ0_F0T_Motherboard_J_brd_V01_OCP.brd")
		(comment 1 "Grand Teton / footprints 1736-1738 of 6105")
	)
	(layers
		(0 "F.Cu" signal "TOP")
		(4 "In1.Cu" signal "GND")
		(6 "In2.Cu" signal "IN1")
		(8 "In3.Cu" signal "GND1")
		(10 "In4.Cu" signal "IN2")
		(12 "In5.Cu" signal "GND2")
		(14 "In6.Cu" signal "IN3")
		(16 "In7.Cu" signal "GND3")
		(18 "In8.Cu" signal "VCC")
		(20 "In9.Cu" signal "VCC1")
		(22 "In10.Cu" signal "GND4")
		(24 "In11.Cu" signal "IN4")
		(26 "In12.Cu" signal "GND5")
		(28 "In13.Cu" signal "IN5")
		(30 "In14.Cu" signal "GND6")
		(32 "In15.Cu" signal "IN6")
		(34 "In16.Cu" signal "GND7")
		(2 "B.Cu" signal "BOTTOM")
		(9 "F.Adhes" user "F.Adhesive")
		(11 "B.Adhes" user "B.Adhesive")
		(13 "F.Paste" user "Package Geometry/Pastemask Top")
		(15 "B.Paste" user "Package Geometry/Pastemask Bottom")
		(5 "F.SilkS" user "Ref Des/Silkscreen Top")
		(7 "B.SilkS" user "Ref Des/Silkscreen Bottom")
		(1 "F.Mask" user "Board Geometry/Soldermask Top")
		(3 "B.Mask" user "Board Geometry/Soldermask Bottom")
		(17 "Dwgs.User" user "User.Drawings")
		(19 "Cmts.User" user "User.Comments")
		(21 "Eco1.User" user "User.Eco1")
		(23 "Eco2.User" user "User.Eco2")
		(25 "Edge.Cuts" user "Board Geometry/Outline")
		(27 "Margin" user)
		(31 "F.CrtYd" user "Package Geometry/Place Bound Top")
		(29 "B.CrtYd" user "Package Geometry/Place Bound Bottom")
		(35 "F.Fab" user "Ref Des/Assembly Top")
		(33 "B.Fab" user "Ref Des/Assembly Bottom")
	)
	(footprint ""
		(layer "F.Cu")
		(at 414.28289 -402.371052 -90)
		(property "Reference" "C963"
			(at 0 0 270)
			(layer "F.SilkS")
			(hide yes)
			(effects
				(font
					(size 1.27 1.27)
				)
			)
		)
		(property "Value" ""
			(at 0 0 270)
			(layer "F.Fab")
			(effects
				(font
					(size 1.27 1.27)
				)
			)
		)
		(duplicate_pad_numbers_are_jumpers no)
		(fp_line
			(start -0.299974 0.150114)
			(end -0.299974 -0.150114)
			(stroke
				(width 0.1)
				(type default)
			)
			(layer "F.Fab")
		)
		(fp_line
			(start 0.299974 0.150114)
			(end -0.299974 0.150114)
			(stroke
				(width 0.1)
				(type default)
			)
			(layer "F.Fab")
		)
		(fp_line
			(start -0.299974 -0.150114)
			(end 0.299974 -0.150114)
			(stroke
				(width 0.1)
				(type default)
			)
			(layer "F.Fab")
		)
		(fp_line
			(start 0.299974 -0.150114)
			(end 0.299974 0.150114)
			(stroke
				(width 0.1)
				(type default)
			)
			(layer "F.Fab")
		)
		(pad "1" smd rect
			(at -0.2667 0 270)
			(size 0.3048 0.381)
			(layers "F.Cu" "F.Mask" "F.Paste")
			(net "P5E_CPU0_PE2_TX_C_DP<1>")
		)
		(pad "2" smd rect
			(at 0.2667 0 270)
			(size 0.3048 0.381)
			(layers "F.Cu" "F.Mask" "F.Paste")
			(net "P5E_CPU0_PE2_TX_DP<1>")
		)
	)
	(footprint ""
		(layer "F.Cu")
		(at 196.729604 -77.06614 180)
		(property "Reference" "R1351"
			(at 0 0 180)
			(layer "F.SilkS")
			(hide yes)
			(effects
				(font
					(size 1.27 1.27)
				)
			)
		)
		(property "Value" ""
			(at 0 0 180)
			(layer "F.Fab")
			(effects
				(font
					(size 1.27 1.27)
				)
			)
		)
		(duplicate_pad_numbers_are_jumpers no)
		(fp_line
			(start 0.7874 0.4064)
			(end -0.7874 0.4064)
			(stroke
				(width 0.1524)
				(type default)
			)
			(layer "F.SilkS")
		)
		(fp_line
			(start 0.7874 -0.4064)
			(end 0.7874 0.4064)
			(stroke
				(width 0.1524)
				(type default)
			)
			(layer "F.SilkS")
		)
		(fp_line
			(start -0.7874 0.4064)
			(end -0.7874 -0.4064)
			(stroke
				(width 0.1524)
				(type default)
			)
			(layer "F.SilkS")
		)
		(fp_line
			(start -0.7874 -0.4064)
			(end 0.7874 -0.4064)
			(stroke
				(width 0.1524)
				(type default)
			)
			(layer "F.SilkS")
		)
		(fp_line
			(start 0.67945 0.3048)
			(end 0.120396 0.3048)
			(stroke
				(width 0.1)
				(type default)
			)
			(layer "F.Fab")
		)
		(fp_line
			(start 0.67945 -0.3048)
			(end 0.67945 0.3048)
			(stroke
				(width 0.1)
				(type default)
			)
			(layer "F.Fab")
		)
		(fp_line
			(start 0.12065 -0.2794)
			(end 0.12065 -0.3048)
			(stroke
				(width 0.1)
				(type default)
			)
			(layer "F.Fab")
		)
		(fp_line
			(start 0.12065 -0.3048)
			(end 0.67945 -0.3048)
			(stroke
				(width 0.1)
				(type default)
			)
			(layer "F.Fab")
		)
		(fp_line
			(start 0.120396 0.3048)
			(end 0.120396 0.2794)
			(stroke
				(width 0.1)
				(type default)
			)
			(layer "F.Fab")
		)
		(fp_line
			(start 0.120396 0.2794)
			(end -0.12065 0.2794)
			(stroke
				(width 0.1)
				(type default)
			)
			(layer "F.Fab")
		)
		(fp_line
			(start -0.12065 0.3048)
			(end -0.67945 0.3048)
			(stroke
				(width 0.1)
				(type default)
			)
			(layer "F.Fab")
		)
		(fp_line
			(start -0.12065 0.2794)
			(end -0.12065 0.3048)
			(stroke
				(width 0.1)
				(type default)
			)
			(layer "F.Fab")
		)
		(fp_line
			(start -0.12065 -0.2794)
			(end 0.12065 -0.2794)
			(stroke
				(width 0.1)
				(type default)
			)
			(layer "F.Fab")
		)
		(fp_line
			(start -0.12065 -0.305054)
			(end -0.12065 -0.2794)
			(stroke
				(width 0.1)
				(type default)
			)
			(layer "F.Fab")
		)
		(fp_line
			(start -0.67945 0.3048)
			(end -0.67945 -0.305054)
			(stroke
				(width 0.1)
				(type default)
			)
			(layer "F.Fab")
		)
		(fp_line
			(start -0.67945 -0.305054)
			(end -0.12065 -0.305054)
			(stroke
				(width 0.1)
				(type default)
			)
			(layer "F.Fab")
		)
		(pad "1" smd circle
			(at -0.40005 0 180)
			(size 0 0)
			(layers "F.Cu" "F.Mask" "F.Paste")
			(net "RMII_OCP_BMC_RXD_0")
		)
		(pad "2" smd circle
			(at 0.40005 0 180)
			(size 0 0)
			(layers "F.Cu" "F.Mask" "F.Paste")
			(net "GND")
		)
	)
	(footprint ""
		(layer "F.Cu")
		(at 384.652012 -347.959426)
		(property "Reference" "PR132"
			(at 0 0 0)
			(layer "F.SilkS")
			(hide yes)
			(effects
				(font
					(size 1.27 1.27)
				)
			)
		)
		(property "Value" ""
			(at 0 0 0)
			(layer "F.Fab")
			(effects
				(font
					(size 1.27 1.27)
				)
			)
		)
		(duplicate_pad_numbers_are_jumpers no)
		(fp_line
			(start -0.7874 -0.4064)
			(end 0.7874 -0.4064)
			(stroke
				(width 0.1524)
				(type default)
			)
			(layer "F.SilkS")
		)
		(fp_line
			(start -0.7874 0.4064)
			(end -0.7874 -0.4064)
			(stroke
				(width 0.1524)
				(type default)
			)
			(layer "F.SilkS")
		)
		(fp_line
			(start 0.7874 -0.4064)
			(end 0.7874 0.4064)
			(stroke
				(width 0.1524)
				(type default)
			)
			(layer "F.SilkS")
		)
		(fp_line
			(start 0.7874 0.4064)
			(end -0.7874 0.4064)
			(stroke
				(width 0.1524)
				(type default)
			)
			(layer "F.SilkS")
		)
		(fp_line
			(start -0.67945 -0.305054)
			(end -0.12065 -0.305054)
			(stroke
				(width 0.1)
				(type default)
			)
			(layer "F.Fab")
		)
		(fp_line
			(start -0.67945 0.3048)
			(end -0.67945 -0.305054)
			(stroke
				(width 0.1)
				(type default)
			)
			(layer "F.Fab")
		)
		(fp_line
			(start -0.12065 -0.305054)
			(end -0.12065 -0.2794)
			(stroke
				(width 0.1)
				(type default)
			)
			(layer "F.Fab")
		)
		(fp_line
			(start -0.12065 -0.2794)
			(end 0.12065 -0.2794)
			(stroke
				(width 0.1)
				(type default)
			)
			(layer "F.Fab")
		)
		(fp_line
			(start -0.12065 0.2794)
			(end -0.12065 0.3048)
			(stroke
				(width 0.1)
				(type default)
			)
			(layer "F.Fab")
		)
		(fp_line
			(start -0.12065 0.3048)
			(end -0.67945 0.3048)
			(stroke
				(width 0.1)
				(type default)
			)
			(layer "F.Fab")
		)
		(fp_line
			(start 0.120396 0.2794)
			(end -0.12065 0.2794)
			(stroke
				(width 0.1)
				(type default)
			)
			(layer "F.Fab")
		)
		(fp_line
			(start 0.120396 0.3048)
			(end 0.120396 0.2794)
			(stroke
				(width 0.1)
				(type default)
			)
			(layer "F.Fab")
		)
		(fp_line
			(start 0.12065 -0.3048)
			(end 0.67945 -0.3048)
			(stroke
				(width 0.1)
				(type default)
			)
			(layer "F.Fab")
		)
		(fp_line
			(start 0.12065 -0.2794)
			(end 0.12065 -0.3048)
			(stroke
				(width 0.1)
				(type default)
			)
			(layer "F.Fab")
		)
		(fp_line
			(start 0.67945 -0.3048)
			(end 0.67945 0.3048)
			(stroke
				(width 0.1)
				(type default)
			)
			(layer "F.Fab")
		)
		(fp_line
			(start 0.67945 0.3048)
			(end 0.120396 0.3048)
			(stroke
				(width 0.1)
				(type default)
			)
			(layer "F.Fab")
		)
		(pad "1" smd circle
			(at -0.40005 0)
			(size 0 0)
			(layers "F.Cu" "F.Mask" "F.Paste")
			(net "PVCCIN_CPU0_LSET8")
		)
		(pad "2" smd circle
			(at 0.40005 0)
			(size 0 0)
			(layers "F.Cu" "F.Mask" "F.Paste")
			(net "GND")
		)
	)
)
